# BARRELEYE_G2-FPDB_POST-EVT-HW-EBOM-X00_20161123-add_2nd_source_X08-20161215-Final-b.xls — Changelist (bom)
| BOM Change List Date:Wed Dec 07 16:22:48 GMT+08:00 2016 |  |  |  |  |  |  |  |  |  |
| New BOM file : BARRELEYE G2-FPDB POST-EVT-HW-EBOM-X00_20161123-add 2nd source_X07-20161207-Final.xls |  |  |  |  |  |  |  |  |  |
| Old BOM file : BARRELEYE G2-FPDB POST-EVT-HW-EBOM-X00_20161123-add 2nd source_X06-20161124.xls |  |  |  |  |  |  |  |  |  |
| ##### Add Parts |  |  |  |  |  |  |  |  |  |
| Item | Location | Qty | Foxconn P/N | Part Description | Manufacturer Full Name | Manufacturer P/N | RoHS | Sheet |  |
| ##### Remove Parts |  |  |  |  |  |  |  |  |  |
| Item | Location | Qty | Foxconn P/N | Part Description | Manufacturer Full Name | Manufacturer P/N | RoHS | Sheet |  |
| ##### Change Parts |  |  |  |  |  |  |  |  |  |
| Item | Location | Qty | Foxconn P/N | Part Description | Manufacturer Full Name | Manufacturer P/N | RoHS | Sheet | Remark |
| 1 | PHAR1 | 1 | 610602200-32D-G | RES,0.5mOhm,+/-1%,3W,G,SMD2512 | Thin Film Technology Corporation | CPA1225RR0005FW |  | PWA BOM | In New BOM |
|  | PHAR1 | 1 | 610602200-32D-G | RES,0.5mOhm,+/-1%,3W,G,SMD2512 | Thin Film Technology Corporation | CPA1225RR0005FW |  | PWA BOM | In Old BOM |
|  |  |  | 610602200-011-G | RES,0.5mOhm,+/-1%,3W,G,SMD2512 | YAGEO | PA2512FKF7T0U5E |  | PWA BOM | In Old BOM |
| 2 | PSRC3 | 1 | 62012GG00-015-G | CAP,10uF,+/-10%,X7S,25V,G,SMD0805 | MURATA | GRM21BC71E106K |  | PWA BOM | In New BOM |
|  |  |  | 62012GG00-012-G | CAP,10uF,+/-10%,X7S,25V,G,SMD0805 | WALSIN | 0805A106K250CT |  | PWA BOM | In New BOM |
|  | PSRC3 | 1 | 62012GG00-015-G | CAP,10uF,+/-10%,X7S,25V,G,SMD0805 | MURATA | GRM21BC71E106K |  | PWA BOM | In Old BOM |
| 3 | PSRC5 | 1 | 62012P100-015-G | CAP,2.2uF,+/-20%,X7S,10V,G,SMD0402 | MURATA | GRM155C71A225M |  | PWA BOM | In New BOM |
|  |  |  | 62012P100-012-G | CAP,2.2uF,+/-20%,X7S,10V,G,SMD0402 | WALSIN | 0402A225M100CT |  | PWA BOM | In New BOM |
|  | PSRC5 | 1 | 62012P100-015-G | CAP,2.2uF,+/-20%,X7S,10V,G,SMD0402 | MURATA | GRM155C71A225M |  | PWA BOM | In Old BOM |
| 4 | C5,C12 | 2 | 620106200-015-G | CAP,10nF,+/-10%,X7R,16V,G,SMD0402 | MURATA | GRM155R71C103KA01D |  | PWA BOM | In New BOM |
|  |  |  | 620106200-012-G | CAP,10nF,+/-10%,X7R,16V,G,SMD0402 | WALSIN | 0402B103K160CT |  | PWA BOM | In New BOM |
|  |  |  | 620106200-026-G | CAP,10nF,+/-10%,X7R,16V,G,SMD0402 | SAMSUNG | CL05B103KO5NNNC |  | PWA BOM | In New BOM |
|  |  |  | 620106200-023-G | CAP,10nF,+/-10%,X7R,16V,G,SMD0402 | TAIYO | EMK105B7103KV-F |  | PWA BOM | In New BOM |
|  | C5,C12 | 2 | 620106205-015-G | CAP,10nF,+/-10%,X7R,16V,G,SMD0402 | MURATA | GRM155R71C103KA01D |  | PWA BOM | In Old BOM |
|  |  |  | 620106200-012-G | CAP,10nF,+/-10%,X7R,16V,G,SMD0402 | WALSIN | 0402B103K160CT |  | PWA BOM | In Old BOM |
|  |  |  | 620106200-026-G | CAP,10nF,+/-10%,X7R,16V,G,SMD0402 | SAMSUNG | CL05B103KO5NNNC |  | PWA BOM | In Old BOM |
|  |  |  | 620106200-023-G | CAP,10nF,+/-10%,X7R,16V,G,SMD0402 | TAIYO | EMK105B7103KV-F |  | PWA BOM | In Old BOM |
| ##### Change Revision |  |  |  |  |  |  |  |  |  |
| Sheet | REV OF BOM | CUSTOMER | CUSTOMER P/N | PWA PN | PWA DESCRIPTION | PWA REV | DATE | Remark |  |
| OOOOOOOOOOOOOOOOOOOOOOOOOOOOOOOOOOOOOOOOOOOOOOOOOOOOOOOOOOOOOOOOOOOOOOOOOOOOOOOOOOOOOOOOOO | OOOOOOOOOOOOOOOOOOOOOOOOOOOOOOOOOOOOOOOOOOOOOOOOOOOOOOOOOOOOOOOOOOOOOOOOOOOOOOOOOOOOOOOOOO | OOOOOOOOOOOOOOOOOOOOOOOOOOOOOOOOOOOOOOOOOOOOOOOOOOOOOOOOOOOOOOOOOOOOOOOOOOOOOOOOOOOOOOOOOO | OOOOOOOOOOOOOOOOOOOOOOOOOOOOOOOOOOOOOOOOOOOOOOOOOOOOOOOOOOOOOOOOOOOOOOOOOOOOOOOOOOOOOOOOOO | OOOOOOOOOOOOOOOOOOOOOOOOOOOOOOOOOOOOOOOOOOOOOOOOOOOOOOOOOOOOOOOOOOOOOOOOOOOOOOOOOOOOOOOOOO | OOOOOOOOOOOOOOOOOOOOOOOOOOOOOOOOOOOOOOOOOOOOOOOOOOOOOOOOOOOOOOOOOOOOOOOOOOOOOOOOOOOOOOOOOO | OOOOOOOOOOOOOOOOOOOOOOOOOOOOOOOOOOOOOOOOOOOOOOOOOOOOOOOOOOOOOOOOOOOOOOOOOOOOOOOOOOOOOOOOOO | OOOOOOOOOOOOOOOOOOOOOOOOOOOOOOOOOOOOOOOOOOOOOOOOOOOOOOOOOOOOOOOOOOOOOOOOOOOOOOOOOOOOOOOOOO | OOOOOOOOOOOOOOOOOOOOOOOOOOOOOOOOOOOOOOOOOOOOOOOOOOOOOOOOOOOOOOOOOOOOOOOOOOOOOOOOOOOOOOOOOO | OOOOOOOOOOOOOOOOOOOOOOOOOOOOOOOOOOOOOOOOOOOOOOOOOOOOOOOOOOOOOOOOOOOOOOOOOOOOOOOOOOOOOOOOOO |
| Second Source Change |  |  |  |  |  |  |  |  |  |
| Item | Location | Change Type | Foxconn P/N | Part Description | Manufacturer Full Name | Manufacturer P/N | RoHS | Sheet |  |
| 1 | PHAR1 |  | 610602200-32D-G | RES,0.5mOhm,+/-1%,3W,G,SMD2512 | Thin Film Technology Corporation | CPA1225RR0005FW |  | PWA BOM |  |
|  |  | Delete | 610602200-011-G | RES,0.5mOhm,+/-1%,3W,G,SMD2512 | YAGEO | PA2512FKF7T0U5E |  | PWA BOM |  |
| 2 | PSRC3 |  | 62012GG00-015-G | CAP,10uF,+/-10%,X7S,25V,G,SMD0805 | MURATA | GRM21BC71E106K |  | PWA BOM |  |
|  |  | ADD | 62012GG00-012-G | CAP,10uF,+/-10%,X7S,25V,G,SMD0805 | WALSIN | 0805A106K250CT |  | PWA BOM |  |
| 3 | PSRC5 |  | 62012P100-015-G | CAP,2.2uF,+/-20%,X7S,10V,G,SMD0402 | MURATA | GRM155C71A225M |  | PWA BOM |  |
|  |  | ADD | 62012P100-012-G | CAP,2.2uF,+/-20%,X7S,10V,G,SMD0402 | WALSIN | 0402A225M100CT |  | PWA BOM |  |
| OOOOOOOOOOOOOOOOOOOOOOOOOOOOOOOOOOOOOOOOOOOOOOOOOOOOOOOOOOOOOOOOOOOOOOOOOOOOOOOOOOOOOOOOOO | OOOOOOOOOOOOOOOOOOOOOOOOOOOOOOOOOOOOOOOOOOOOOOOOOOOOOOOOOOOOOOOOOOOOOOOOOOOOOOOOOOOOOOOOOO | OOOOOOOOOOOOOOOOOOOOOOOOOOOOOOOOOOOOOOOOOOOOOOOOOOOOOOOOOOOOOOOOOOOOOOOOOOOOOOOOOOOOOOOOOO | OOOOOOOOOOOOOOOOOOOOOOOOOOOOOOOOOOOOOOOOOOOOOOOOOOOOOOOOOOOOOOOOOOOOOOOOOOOOOOOOOOOOOOOOOO | OOOOOOOOOOOOOOOOOOOOOOOOOOOOOOOOOOOOOOOOOOOOOOOOOOOOOOOOOOOOOOOOOOOOOOOOOOOOOOOOOOOOOOOOOO | OOOOOOOOOOOOOOOOOOOOOOOOOOOOOOOOOOOOOOOOOOOOOOOOOOOOOOOOOOOOOOOOOOOOOOOOOOOOOOOOOOOOOOOOOO | OOOOOOOOOOOOOOOOOOOOOOOOOOOOOOOOOOOOOOOOOOOOOOOOOOOOOOOOOOOOOOOOOOOOOOOOOOOOOOOOOOOOOOOOOO | OOOOOOOOOOOOOOOOOOOOOOOOOOOOOOOOOOOOOOOOOOOOOOOOOOOOOOOOOOOOOOOOOOOOOOOOOOOOOOOOOOOOOOOOOO | OOOOOOOOOOOOOOOOOOOOOOOOOOOOOOOOOOOOOOOOOOOOOOOOOOOOOOOOOOOOOOOOOOOOOOOOOOOOOOOOOOOOOOOOOO | OOOOOOOOOOOOOOOOOOOOOOOOOOOOOOOOOOOOOOOOOOOOOOOOOOOOOOOOOOOOOOOOOOOOOOOOOOOOOOOOOOOOOOOOOO |
| Master Materials Change |  |  |  |  |  |  |  |  |  |
| Item | Foxconn P/N | Orig._Usage | New_Usage | Part Description | Manufacturer Full Name | Manufacturer P/N | RoHS | Location | Sheet |
| 1 | 620106200-015-G | 0 | 2 | CAP,10nF,+/-10%,X7R,16V,G,SMD0402 | MURATA | GRM155R71C103KA01D |  | (+)C5,C12 | PWA BOM |
|  | 620106200-012-G |  |  | CAP,10nF,+/-10%,X7R,16V,G,SMD0402 | WALSIN | 0402B103K160CT |  |  | PWA BOM |
|  | 620106200-026-G |  |  | CAP,10nF,+/-10%,X7R,16V,G,SMD0402 | SAMSUNG | CL05B103KO5NNNC |  |  | PWA BOM |
|  | 620106200-023-G |  |  | CAP,10nF,+/-10%,X7R,16V,G,SMD0402 | TAIYO | EMK105B7103KV-F |  |  | PWA BOM |
| 2 | 620106205-015-G | 2 | 0 | CAP,10nF,+/-10%,X7R,16V,G,SMD0402 | MURATA | GRM155R71C103KA01D |  | (-)C5,C12 | PWA BOM |
|  | 620106200-012-G |  |  | CAP,10nF,+/-10%,X7R,16V,G,SMD0402 | WALSIN | 0402B103K160CT |  |  | PWA BOM |
|  | 620106200-026-G |  |  | CAP,10nF,+/-10%,X7R,16V,G,SMD0402 | SAMSUNG | CL05B103KO5NNNC |  |  | PWA BOM |
|  | 620106200-023-G |  |  | CAP,10nF,+/-10%,X7R,16V,G,SMD0402 | TAIYO | EMK105B7103KV-F |  |  | PWA BOM |
| OOOOOOOOOOOOOOOOOOOOOOOOOOOOOOOOOOOOOOOOOOOOOOOOOOOOOOOOOOOOOOOOOOOOOOOOOOOOOOOOOOOOOOOOOO | OOOOOOOOOOOOOOOOOOOOOOOOOOOOOOOOOOOOOOOOOOOOOOOOOOOOOOOOOOOOOOOOOOOOOOOOOOOOOOOOOOOOOOOOOO | OOOOOOOOOOOOOOOOOOOOOOOOOOOOOOOOOOOOOOOOOOOOOOOOOOOOOOOOOOOOOOOOOOOOOOOOOOOOOOOOOOOOOOOOOO | OOOOOOOOOOOOOOOOOOOOOOOOOOOOOOOOOOOOOOOOOOOOOOOOOOOOOOOOOOOOOOOOOOOOOOOOOOOOOOOOOOOOOOOOOO | OOOOOOOOOOOOOOOOOOOOOOOOOOOOOOOOOOOOOOOOOOOOOOOOOOOOOOOOOOOOOOOOOOOOOOOOOOOOOOOOOOOOOOOOOO | OOOOOOOOOOOOOOOOOOOOOOOOOOOOOOOOOOOOOOOOOOOOOOOOOOOOOOOOOOOOOOOOOOOOOOOOOOOOOOOOOOOOOOOOOO | OOOOOOOOOOOOOOOOOOOOOOOOOOOOOOOOOOOOOOOOOOOOOOOOOOOOOOOOOOOOOOOOOOOOOOOOOOOOOOOOOOOOOOOOOO | OOOOOOOOOOOOOOOOOOOOOOOOOOOOOOOOOOOOOOOOOOOOOOOOOOOOOOOOOOOOOOOOOOOOOOOOOOOOOOOOOOOOOOOOOO | OOOOOOOOOOOOOOOOOOOOOOOOOOOOOOOOOOOOOOOOOOOOOOOOOOOOOOOOOOOOOOOOOOOOOOOOOOOOOOOOOOOOOOOOOO |  |
| TLA Parts Change |  |  |  |  |  |  |  |  |  |
| Item | Foxconn P/N | Qty | Part Description | Manufacturer Full Name | Manufacturer P/N | RoHS | Location | Remark |  |
| BOM Change List Date:Wed Dec 15 16:22:48 GMT+08:00 2016 |  |  |  |  |  |  |  |  |  |
| New BOM file : BARRELEYE G2-FPDB POST-EVT-HW-EBOM-X00_20161123-add 2nd source_X08-20161215-Final-b.xls |  |  |  |  |  |  |  |  |  |
| Old BOM file : BARRELEYE G2-FPDB POST-EVT-HW-EBOM-X00_20161123-add 2nd source_X07-20161209.xls |  |  |  |  |  |  |  |  |  |
| ##### Add Parts |  |  |  |  |  |  |  |  |  |
| Item | Location | Qty | Foxconn P/N | Part Description | Manufacturer Full Name | Manufacturer P/N | RoHS | Sheet |  |
| 1 | U27 | 1 | 320245F00-173-G | IC,Power Controller,MAX6456UT29S+T,G,SOT-23-6,SMD | MAXIM | MAX6456UT29S+T |  | FPDB |  |
| ##### Remove Parts |  |  |  |  |  |  |  |  |  |
| Item | Location | Qty | Foxconn P/N | Part Description | Manufacturer Full Name | Manufacturer P/N | RoHS | Sheet |  |
| 1 | PHAU2 | 1 | 320245F00-173-G | IC,Power Controller,MAX6456UT29S+T,G,SOT-23-6,SMD | MAXIM | MAX6456UT29S+T |  | FPDB |  |
| ##### Change Parts |  |  |  |  |  |  |  |  |  |
| Item | Location | Qty | Foxconn P/N | Part Description | Manufacturer Full Name | Manufacturer P/N | RoHS | Sheet | Remark |
| ##### Change Revision |  |  |  |  |  |  |  |  |  |
| Sheet | REV OF BOM | CUSTOMER | CUSTOMER P/N | PWA PN | PWA DESCRIPTION | PWA REV | DATE | Remark |  |
| PWA | X08 | Rackspace |  |  |  |  |  |  |  |
| PWA | X07 | Rackspace |  |  |  |  |  |  |  |
| OOOOOOOOOOOOOOOOOOOOOOOOOOOOOOOOOOOOOOOOOOOOOOOOOOOOOOOOOOOOOOOOOOOOOOOOOOOOOOOOOOOOOOOOOO | OOOOOOOOOOOOOOOOOOOOOOOOOOOOOOOOOOOOOOOOOOOOOOOOOOOOOOOOOOOOOOOOOOOOOOOOOOOOOOOOOOOOOOOOOO | OOOOOOOOOOOOOOOOOOOOOOOOOOOOOOOOOOOOOOOOOOOOOOOOOOOOOOOOOOOOOOOOOOOOOOOOOOOOOOOOOOOOOOOOOO | OOOOOOOOOOOOOOOOOOOOOOOOOOOOOOOOOOOOOOOOOOOOOOOOOOOOOOOOOOOOOOOOOOOOOOOOOOOOOOOOOOOOOOOOOO | OOOOOOOOOOOOOOOOOOOOOOOOOOOOOOOOOOOOOOOOOOOOOOOOOOOOOOOOOOOOOOOOOOOOOOOOOOOOOOOOOOOOOOOOOO | OOOOOOOOOOOOOOOOOOOOOOOOOOOOOOOOOOOOOOOOOOOOOOOOOOOOOOOOOOOOOOOOOOOOOOOOOOOOOOOOOOOOOOOOOO | OOOOOOOOOOOOOOOOOOOOOOOOOOOOOOOOOOOOOOOOOOOOOOOOOOOOOOOOOOOOOOOOOOOOOOOOOOOOOOOOOOOOOOOOOO | OOOOOOOOOOOOOOOOOOOOOOOOOOOOOOOOOOOOOOOOOOOOOOOOOOOOOOOOOOOOOOOOOOOOOOOOOOOOOOOOOOOOOOOOOO | OOOOOOOOOOOOOOOOOOOOOOOOOOOOOOOOOOOOOOOOOOOOOOOOOOOOOOOOOOOOOOOOOOOOOOOOOOOOOOOOOOOOOOOOOO | OOOOOOOOOOOOOOOOOOOOOOOOOOOOOOOOOOOOOOOOOOOOOOOOOOOOOOOOOOOOOOOOOOOOOOOOOOOOOOOOOOOOOOOOOO |
| Second Source Change |  |  |  |  |  |  |  |  |  |
| Item | Location | Change Type | Foxconn P/N | Part Description | Manufacturer Full Name | Manufacturer P/N | RoHS | Sheet |  |
| OOOOOOOOOOOOOOOOOOOOOOOOOOOOOOOOOOOOOOOOOOOOOOOOOOOOOOOOOOOOOOOOOOOOOOOOOOOOOOOOOOOOOOOOOO | OOOOOOOOOOOOOOOOOOOOOOOOOOOOOOOOOOOOOOOOOOOOOOOOOOOOOOOOOOOOOOOOOOOOOOOOOOOOOOOOOOOOOOOOOO | OOOOOOOOOOOOOOOOOOOOOOOOOOOOOOOOOOOOOOOOOOOOOOOOOOOOOOOOOOOOOOOOOOOOOOOOOOOOOOOOOOOOOOOOOO | OOOOOOOOOOOOOOOOOOOOOOOOOOOOOOOOOOOOOOOOOOOOOOOOOOOOOOOOOOOOOOOOOOOOOOOOOOOOOOOOOOOOOOOOOO | OOOOOOOOOOOOOOOOOOOOOOOOOOOOOOOOOOOOOOOOOOOOOOOOOOOOOOOOOOOOOOOOOOOOOOOOOOOOOOOOOOOOOOOOOO | OOOOOOOOOOOOOOOOOOOOOOOOOOOOOOOOOOOOOOOOOOOOOOOOOOOOOOOOOOOOOOOOOOOOOOOOOOOOOOOOOOOOOOOOOO | OOOOOOOOOOOOOOOOOOOOOOOOOOOOOOOOOOOOOOOOOOOOOOOOOOOOOOOOOOOOOOOOOOOOOOOOOOOOOOOOOOOOOOOOOO | OOOOOOOOOOOOOOOOOOOOOOOOOOOOOOOOOOOOOOOOOOOOOOOOOOOOOOOOOOOOOOOOOOOOOOOOOOOOOOOOOOOOOOOOOO | OOOOOOOOOOOOOOOOOOOOOOOOOOOOOOOOOOOOOOOOOOOOOOOOOOOOOOOOOOOOOOOOOOOOOOOOOOOOOOOOOOOOOOOOOO | OOOOOOOOOOOOOOOOOOOOOOOOOOOOOOOOOOOOOOOOOOOOOOOOOOOOOOOOOOOOOOOOOOOOOOOOOOOOOOOOOOOOOOOOOO |
| Master Materials Change |  |  |  |  |  |  |  |  |  |
| Item | Foxconn P/N | Orig._Usage | New_Usage | Part Description | Manufacturer Full Name | Manufacturer P/N | RoHS | Location | Sheet |
| 1 | 320245F00-173-G | 0 | 1 | IC,Power Controller,MAX6456UT29S+T,G,SOT-23-6,SMD | MAXIM | MAX6456UT29S+T |  | (+)PHAU2 | FPDB BOM |
| 2 | 320245F00-173-G | 1 | 0 | IC,Power Controller,MAX6456UT29S+T,G,SOT-23-6,SMD | MAXIM | MAX6456UT29S+T |  | (-)U27 | FPDB BOM |
| OOOOOOOOOOOOOOOOOOOOOOOOOOOOOOOOOOOOOOOOOOOOOOOOOOOOOOOOOOOOOOOOOOOOOOOOOOOOOOOOOOOOOOOOOO | OOOOOOOOOOOOOOOOOOOOOOOOOOOOOOOOOOOOOOOOOOOOOOOOOOOOOOOOOOOOOOOOOOOOOOOOOOOOOOOOOOOOOOOOOO | OOOOOOOOOOOOOOOOOOOOOOOOOOOOOOOOOOOOOOOOOOOOOOOOOOOOOOOOOOOOOOOOOOOOOOOOOOOOOOOOOOOOOOOOOO | OOOOOOOOOOOOOOOOOOOOOOOOOOOOOOOOOOOOOOOOOOOOOOOOOOOOOOOOOOOOOOOOOOOOOOOOOOOOOOOOOOOOOOOOOO | OOOOOOOOOOOOOOOOOOOOOOOOOOOOOOOOOOOOOOOOOOOOOOOOOOOOOOOOOOOOOOOOOOOOOOOOOOOOOOOOOOOOOOOOOO | OOOOOOOOOOOOOOOOOOOOOOOOOOOOOOOOOOOOOOOOOOOOOOOOOOOOOOOOOOOOOOOOOOOOOOOOOOOOOOOOOOOOOOOOOO | OOOOOOOOOOOOOOOOOOOOOOOOOOOOOOOOOOOOOOOOOOOOOOOOOOOOOOOOOOOOOOOOOOOOOOOOOOOOOOOOOOOOOOOOOO | OOOOOOOOOOOOOOOOOOOOOOOOOOOOOOOOOOOOOOOOOOOOOOOOOOOOOOOOOOOOOOOOOOOOOOOOOOOOOOOOOOOOOOOOOO | OOOOOOOOOOOOOOOOOOOOOOOOOOOOOOOOOOOOOOOOOOOOOOOOOOOOOOOOOOOOOOOOOOOOOOOOOOOOOOOOOOOOOOOOOO |  |
| TLA Parts Change |  |  |  |  |  |  |  |  |  |
| Item | Foxconn P/N | Qty | Part Description | Manufacturer Full Name | Manufacturer P/N | RoHS | Location | Remark |  |
